FILE_TYPE = CONNECTIVITY;
{Allegro Design Entry HDL 16.6-p007 (v16-6-112F) 10/10/2012}
"PAGE_NUMBER" = 41;
0"NC";
1"GND\g";
2"GND\g";
3"GND\g";
4"GND\g";
5"GND\g";
6"GND\g";
7"GND\g";
8"GND\g";
%"GND"
"1","(-4475,550)","0","mstr_symbols","I275";
;
VOLTAGE"0.0V"
SIZE"1B"
CDS_LIB"mstr_symbols"
BODY_TYPE"PLUMBING"
HDL_POWER"GND";
"A\NAC"1;
%"GND"
"1","(-2800,525)","0","mstr_symbols","I276";
;
VOLTAGE"0.0V"
SIZE"1B"
CDS_LIB"mstr_symbols"
BODY_TYPE"PLUMBING"
HDL_POWER"GND";
"A\NAC"2;
%"GND"
"1","(-1075,475)","0","mstr_symbols","I277";
;
VOLTAGE"0.0V"
SIZE"1B"
CDS_LIB"mstr_symbols"
BODY_TYPE"PLUMBING"
HDL_POWER"GND";
"A\NAC"3;
%"GND"
"1","(-6025,550)","0","mstr_symbols","I278";
;
VOLTAGE"0.0V"
SIZE"1B"
CDS_LIB"mstr_symbols"
BODY_TYPE"PLUMBING"
HDL_POWER"GND";
"A\NAC"4;
%"GND"
"1","(-4350,550)","0","mstr_symbols","I279";
;
VOLTAGE"0.0V"
SIZE"1B"
CDS_LIB"mstr_symbols"
BODY_TYPE"PLUMBING"
HDL_POWER"GND";
"A\NAC"5;
%"GND"
"1","(-2625,500)","0","mstr_symbols","I280";
;
VOLTAGE"0.0V"
SIZE"1B"
CDS_LIB"mstr_symbols"
BODY_TYPE"PLUMBING"
HDL_POWER"GND";
"A\NAC"6;
%"GND"
"1","(-925,475)","0","mstr_symbols","I281";
;
VOLTAGE"0.0V"
SIZE"1B"
CDS_LIB"mstr_symbols"
BODY_TYPE"PLUMBING"
HDL_POWER"GND";
"A\NAC"7;
%"GND"
"1","(600,1650)","0","mstr_symbols","I282";
;
VOLTAGE"0.0V"
SIZE"1B"
CDS_LIB"mstr_symbols"
BODY_TYPE"PLUMBING"
HDL_POWER"GND";
"A\NAC"8;
%"SKX_EXT_B"
"27","(-5275,2650)","0","chpset_lib","I283";
;
CDS_SEC"27"
LOCATION"U5D1"
PART_NUMBER"TBD"
MATERIAL"IC"
PACK_TYPE"BGA1"
CDS_LIB"chpset_lib"
SEC_TYPE"BGA1"
SEC"27"
CDS_LOCATION"U5D1"
ROOM"CPU0";
"VSS<454>"
$PN"P49"1;
"VSS<455>"
$PN"CJ12"1;
"VSS<456>"
$PN"CJ10"1;
"VSS<457>"
$PN"CJ8"1;
"VSS<458>"
$PN"CJ6"1;
"VSS<459>"
$PN"CJ2"1;
"VSS<460>"
$PN"CH83"1;
"VSS<461>"
$PN"CH81"1;
"VSS<462>"
$PN"CH79"1;
"VSS<463>"
$PN"CH73"1;
"VSS<464>"
$PN"CH67"1;
"VSS<465>"
$PN"CH63"1;
"VSS<466>"
$PN"CH19"1;
"VSS<467>"
$PN"CH15"1;
"VSS<468>"
$PN"CH3"1;
"VSS<469>"
$PN"CH1"1;
"VSS<470>"
$PN"CG80"1;
"VSS<471>"
$PN"CG72"1;
"VSS<472>"
$PN"CG68"1;
"VSS<473>"
$PN"CG62"1;
"VSS<474>"
$PN"CG22"1;
"VSS<475>"
$PN"CG18"1;
"VSS<476>"
$PN"P51"1;
"VSS<477>"
$PN"CF83"1;
"VSS<478>"
$PN"CF77"1;
"VSS<479>"
$PN"CF71"1;
"VSS<480>"
$PN"CF69"1;
"VSS<481>"
$PN"CF63"1;
"VSS<482>"
$PN"CF9"1;
"VSS<483>"
$PN"P53"1;
"VSS<484>"
$PN"CE82"1;
"VSS<485>"
$PN"CE70"1;
"VSS<486>"
$PN"CE62"1;
"VSS<487>"
$PN"CE26"1;
"VSS<488>"
$PN"CE20"1;
"VSS<489>"
$PN"CE14"1;
"VSS<490>"
$PN"CE10"1;
"VSS<491>"
$PN"CD81"1;
"VSS<492>"
$PN"CD79"1;
"VSS<493>"
$PN"CD77"1;
"VSS<494>"
$PN"CD75"1;
"VSS<495>"
$PN"CD73"1;
"VSS<496>"
$PN"CD63"1;
"VSS<497>"
$PN"CD13"1;
"VSS<498>"
$PN"CD5"1;
"VSS<499>"
$PN"CC82"1;
"VSS<500>"
$PN"CC80"1;
"VSS<501>"
$PN"CC78"1;
"VSS<502>"
$PN"CC76"1;
"VSS<503>"
$PN"CC74"1;
"VSS<504>"
$PN"CC72"1;
"VSS<505>"
$PN"CC64"1;
"VSS<506>"
$PN"CC24"1;
"VSS<507>"
$PN"CC18"1;
"VSS<508>"
$PN"CC16"1;
"VSS<509>"
$PN"CC4"1;
"VSS<510>"
$PN"CB71"1;
"VSS<511>"
$PN"CB63"1;
"VSS<512>"
$PN"CB27"1;
"VSS<513>"
$PN"CB9"1;
"VSS<514>"
$PN"CB7"1;
"VSS<515>"
$PN"CA70"1;
"VSS<516>"
$PN"CA68"1;
"VSS<517>"
$PN"CA66"1;
"VSS<518>"
$PN"CA64"1;
"VSS<519>"
$PN"CA26"1;
"VSS<520>"
$PN"CA18"1;
"VSS<521>"
$PN"CA14"1;
"VSS<522>"
$PN"CA10"1;
"VSS<523>"
$PN"CA8"1;
"VSS<524>"
$PN"CA6"1;
"VSS<525>"
$PN"CA2"1;
"VSS<526>"
$PN"BY71"1;
"VSS<527>"
$PN"BY69"1;
"VSS<528>"
$PN"BY67"1;
"VSS<529>"
$PN"BY65"1;
"VSS<530>"
$PN"BY63"1;
"VSS<531>"
$PN"BY23"1;
"VSS<532>"
$PN"BY13"1;
"VSS<533>"
$PN"BY11"1;
"VSS<534>"
$PN"BW82"4;
"VSS<535>"
$PN"BW80"4;
"VSS<536>"
$PN"BW78"4;
"VSS<537>"
$PN"BW76"4;
"VSS<538>"
$PN"BW74"4;
"VSS<539>"
$PN"BW72"4;
"VSS<540>"
$PN"BW26"4;
"VSS<541>"
$PN"BW18"4;
"VSS<542>"
$PN"BW16"4;
"VSS<543>"
$PN"BW14"4;
"VSS<544>"
$PN"BW12"4;
"VSS<545>"
$PN"P55"4;
"VSS<546>"
$PN"BW6"4;
"VSS<547>"
$PN"BV25"4;
"VSS<548>"
$PN"BV17"4;
"VSS<549>"
$PN"BU10"4;
"VSS<550>"
$PN"BV5"4;
"VSS<551>"
$PN"BU8"4;
"VSS<552>"
$PN"BT25"4;
"VSS<553>"
$PN"BT23"4;
"VSS<554>"
$PN"BT21"4;
"VSS<555>"
$PN"BT5"4;
"VSS<556>"
$PN"BT3"4;
"VSS<557>"
$PN"BR82"4;
"VSS<558>"
$PN"BR80"4;
"VSS<559>"
$PN"BR78"4;
"VSS<560>"
$PN"BR76"4;
"VSS<561>"
$PN"BR74"4;
"VSS<562>"
$PN"BR72"4;
"VSS<563>"
$PN"BR70"4;
"VSS<564>"
$PN"BR68"4;
"VSS<565>"
$PN"BR66"4;
"VSS<566>"
$PN"BR64"4;
"VSS<567>"
$PN"P57"4;
"VSS<568>"
$PN"BR16"4;
"VSS<569>"
$PN"BR10"4;
"VSS<570>"
$PN"BR6"4;
"VSS<571>"
$PN"BP27"4;
"VSS<572>"
$PN"BP3"4;
"VSS<573>"
$PN"BN26"4;
"VSS<574>"
$PN"BN20"4;
"VSS<575>"
$PN"BN10"4;
"VSS<576>"
$PN"BN6"4;
"VSS<577>"
$PN"BM25"4;
"VSS<578>"
$PN"P59"4;
"VSS<579>"
$PN"BM15"4;
"VSS<580>"
$PN"BM13"4;
"VSS<581>"
$PN"BM9"4;
"VSS<582>"
$PN"BL82"4;
"VSS<583>"
$PN"BL80"4;
"VSS<584>"
$PN"BL78"4;
"VSS<585>"
$PN"BL76"4;
"VSS<586>"
$PN"BL74"4;
"VSS<587>"
$PN"BL72"4;
"VSS<588>"
$PN"BL70"4;
"VSS<589>"
$PN"BL68"4;
"VSS<590>"
$PN"BL66"4;
"VSS<591>"
$PN"BL64"4;
"VSS<592>"
$PN"BL24"4;
"VSS<593>"
$PN"BL22"4;
"VSS<594>"
$PN"P61"4;
"VSS<595>"
$PN"BL12"4;
"VSS<596>"
$PN"BL10"4;
"VSS<597>"
$PN"BL6"4;
"VSS<598>"
$PN"BK19"4;
"VSS<599>"
$PN"BK11"4;
"VSS<600>"
$PN"BK7"4;
"VSS<601>"
$PN"BK3"4;
"VSS<602>"
$PN"BJ6"4;
"VSS<603>"
$PN"BJ4"4;
"VSS<604>"
$PN"BH21"4;
"VSS<605>"
$PN"BH15"4;
"VSS<606>"
$PN"BH11"4;
"VSS<607>"
$PN"BH9"4;
"VSS<608>"
$PN"BH7"4;
"VSS<609>"
$PN"BG82"4;
"VSS<610>"
$PN"BG80"4;
"VSS<611>"
$PN"BG78"4;
"VSS<612>"
$PN"BG76"4;
"VSS<613>"
$PN"BG74"4;
%"SKX_EXT_B"
"28","(-3575,2650)","0","chpset_lib","I284";
;
CDS_SEC"28"
LOCATION"U5D1"
PART_NUMBER"TBD"
MATERIAL"IC"
PACK_TYPE"BGA1"
CDS_LIB"chpset_lib"
SEC_TYPE"BGA1"
SEC"28"
CDS_LOCATION"U5D1"
ROOM"CPU0";
"VSS<294>"
$PN"DA46"2;
"VSS<295>"
$PN"DA44"2;
"VSS<296>"
$PN"DA38"2;
"VSS<297>"
$PN"DA36"2;
"VSS<298>"
$PN"DA34"2;
"VSS<299>"
$PN"DA32"2;
"VSS<300>"
$PN"DA30"2;
"VSS<301>"
$PN"DA28"2;
"VSS<302>"
$PN"DA26"2;
"VSS<303>"
$PN"DA18"2;
"VSS<304>"
$PN"H53"2;
"VSS<305>"
$PN"DA6"2;
"VSS<306>"
$PN"CY85"2;
"VSS<307>"
$PN"CY83"2;
"VSS<308>"
$PN"CY77"2;
"VSS<309>"
$PN"CY75"2;
"VSS<310>"
$PN"CY69"2;
"VSS<311>"
$PN"CY65"2;
"VSS<312>"
$PN"CY61"2;
"VSS<313>"
$PN"CY59"2;
"VSS<314>"
$PN"CY51"2;
"VSS<315>"
$PN"CY45"2;
"VSS<316>"
$PN"CY41"2;
"VSS<317>"
$PN"CY21"2;
"VSS<318>"
$PN"CY15"2;
"VSS<319>"
$PN"CY13"2;
"VSS<320>"
$PN"CY9"2;
"VSS<321>"
$PN"CY1"2;
"VSS<322>"
$PN"CW82"2;
"VSS<323>"
$PN"CW78"2;
"VSS<324>"
$PN"CW74"2;
"VSS<325>"
$PN"CW68"2;
"VSS<326>"
$PN"CW66"2;
"VSS<327>"
$PN"CW64"2;
"VSS<328>"
$PN"CW54"2;
"VSS<329>"
$PN"CW52"2;
"VSS<330>"
$PN"CW42"2;
"VSS<331>"
$PN"CW40"2;
"VSS<332>"
$PN"CW38"2;
"VSS<333>"
$PN"CW32"2;
"VSS<334>"
$PN"CW26"2;
"VSS<335>"
$PN"CW12"2;
"VSS<336>"
$PN"CV83"2;
"VSS<337>"
$PN"CV81"2;
"VSS<338>"
$PN"CV79"2;
"VSS<339>"
$PN"CV73"2;
"VSS<340>"
$PN"CV67"2;
"VSS<341>"
$PN"CV63"2;
"VSS<342>"
$PN"CV55"2;
"VSS<343>"
$PN"CV53"2;
"VSS<344>"
$PN"CV41"2;
"VSS<345>"
$PN"CV39"2;
"VSS<346>"
$PN"CV37"2;
"VSS<347>"
$PN"CV33"2;
"VSS<348>"
$PN"CV31"2;
"VSS<349>"
$PN"CV27"2;
"VSS<350>"
$PN"CV25"2;
"VSS<351>"
$PN"CV17"2;
"VSS<352>"
$PN"H55"2;
"VSS<353>"
$PN"CV1"2;
"VSS<354>"
$PN"CU86"2;
"VSS<355>"
$PN"CU82"2;
"VSS<356>"
$PN"CU80"2;
"VSS<357>"
$PN"CU78"2;
"VSS<358>"
$PN"CU76"2;
"VSS<359>"
$PN"CU68"2;
"VSS<360>"
$PN"CU62"2;
"VSS<361>"
$PN"CU56"2;
"VSS<362>"
$PN"CU36"2;
"VSS<363>"
$PN"CU34"2;
"VSS<364>"
$PN"CU30"2;
"VSS<365>"
$PN"CU28"2;
"VSS<366>"
$PN"CU22"2;
"VSS<367>"
$PN"CU4"2;
"VSS<368>"
$PN"CT85"2;
"VSS<369>"
$PN"CT83"2;
"VSS<370>"
$PN"CT79"2;
"VSS<371>"
$PN"CT73"2;
"VSS<372>"
$PN"CT57"2;
"VSS<373>"
$PN"CT35"2;
"VSS<374>"
$PN"CT33"5;
"VSS<375>"
$PN"CT29"5;
"VSS<376>"
$PN"CT27"5;
"VSS<377>"
$PN"CT19"5;
"VSS<378>"
$PN"CT13"5;
"VSS<379>"
$PN"H57"5;
"VSS<380>"
$PN"CR86"5;
"VSS<381>"
$PN"CR78"5;
"VSS<382>"
$PN"CR68"5;
"VSS<383>"
$PN"CR66"5;
"VSS<384>"
$PN"CR64"5;
"VSS<385>"
$PN"CR62"5;
"VSS<386>"
$PN"CR58"5;
"VSS<387>"
$PN"CR32"5;
"VSS<388>"
$PN"CR24"5;
"VSS<389>"
$PN"CR22"5;
"VSS<390>"
$PN"CR10"5;
"VSS<391>"
$PN"CR6"5;
"VSS<392>"
$PN"CP83"5;
"VSS<393>"
$PN"CP81"5;
"VSS<394>"
$PN"CP75"5;
"VSS<395>"
$PN"CP73"5;
"VSS<396>"
$PN"CP69"5;
"VSS<397>"
$PN"CP59"5;
"VSS<398>"
$PN"CP25"5;
"VSS<399>"
$PN"H59"5;
"VSS<400>"
$PN"CP1"5;
"VSS<401>"
$PN"CN78"5;
"VSS<402>"
$PN"CN68"5;
"VSS<403>"
$PN"CN62"5;
"VSS<404>"
$PN"CN60"5;
"VSS<405>"
$PN"CN32"5;
"VSS<406>"
$PN"CN26"5;
"VSS<407>"
$PN"H61"5;
"VSS<408>"
$PN"CN12"5;
"VSS<409>"
$PN"CN2"5;
"VSS<410>"
$PN"CM85"5;
"VSS<411>"
$PN"CM83"5;
"VSS<412>"
$PN"CM77"5;
"VSS<413>"
$PN"CM73"5;
"VSS<414>"
$PN"CM67"5;
"VSS<415>"
$PN"CM63"5;
"VSS<416>"
$PN"CM61"5;
"VSS<417>"
$PN"CM31"5;
"VSS<418>"
$PN"CM5"5;
"VSS<419>"
$PN"CM29"5;
"VSS<420>"
$PN"CM19"5;
"VSS<421>"
$PN"CL80"5;
"VSS<422>"
$PN"CL78"5;
"VSS<423>"
$PN"CL76"5;
"VSS<424>"
$PN"CL74"5;
"VSS<425>"
$PN"CL66"5;
"VSS<426>"
$PN"CL64"5;
"VSS<427>"
$PN"CL62"5;
"VSS<428>"
$PN"H63"5;
"VSS<429>"
$PN"P45"5;
"VSS<430>"
$PN"CL18"5;
"VSS<431>"
$PN"CL14"5;
"VSS<432>"
$PN"CL8"5;
"VSS<433>"
$PN"CK85"5;
"VSS<434>"
$PN"CK83"5;
"VSS<435>"
$PN"CK75"5;
"VSS<436>"
$PN"CK73"5;
"VSS<437>"
$PN"CK71"5;
"VSS<438>"
$PN"CK69"5;
"VSS<439>"
$PN"CK67"5;
"VSS<440>"
$PN"CK65"5;
"VSS<441>"
$PN"CK63"5;
"VSS<442>"
$PN"CK27"5;
"VSS<443>"
$PN"CK21"5;
"VSS<444>"
$PN"CK15"5;
"VSS<445>"
$PN"CK11"5;
"VSS<446>"
$PN"CJ86"5;
"VSS<447>"
$PN"CJ84"5;
"VSS<448>"
$PN"CJ82"5;
"VSS<449>"
$PN"CJ78"5;
"VSS<450>"
$PN"CJ76"5;
"VSS<451>"
$PN"CJ74"5;
"VSS<452>"
$PN"CJ62"5;
"VSS<453>"
$PN"P47"5;
%"SKX_EXT_B"
"29","(-1850,2600)","0","chpset_lib","I285";
;
CDS_SEC"29"
LOCATION"U5D1"
PART_NUMBER"TBD"
MATERIAL"IC"
PACK_TYPE"BGA1"
CDS_LIB"chpset_lib"
SEC_TYPE"BGA1"
SEC"29"
CDS_LOCATION"U5D1"
ROOM"CPU0";
"VSS<134>"
$PN"DN72"3;
"VSS<135>"
$PN"DN68"3;
"VSS<136>"
$PN"DN38"3;
"VSS<137>"
$PN"DN32"3;
"VSS<138>"
$PN"DN26"3;
"VSS<139>"
$PN"DN22"3;
"VSS<140>"
$PN"DN12"3;
"VSS<141>"
$PN"BH17"3;
"VSS<142>"
$PN"DN2"3;
"VSS<143>"
$PN"DM83"3;
"VSS<144>"
$PN"DM77"3;
"VSS<145>"
$PN"DM73"3;
"VSS<146>"
$PN"DM65"3;
"VSS<147>"
$PN"DM39"3;
"VSS<148>"
$PN"DM37"3;
"VSS<149>"
$PN"DM33"3;
"VSS<150>"
$PN"DM31"3;
"VSS<151>"
$PN"DM27"3;
"VSS<152>"
$PN"DM25"3;
"VSS<153>"
$PN"H45"3;
"VSS<154>"
$PN"DM15"3;
"VSS<155>"
$PN"DL80"3;
"VSS<156>"
$PN"DL78"3;
"VSS<157>"
$PN"DL76"3;
"VSS<158>"
$PN"DL74"3;
"VSS<159>"
$PN"DL70"3;
"VSS<160>"
$PN"DL68"3;
"VSS<161>"
$PN"DL40"3;
"VSS<162>"
$PN"DL36"3;
"VSS<163>"
$PN"DL34"3;
"VSS<164>"
$PN"DL30"3;
"VSS<165>"
$PN"DL28"3;
"VSS<166>"
$PN"DL24"3;
"VSS<167>"
$PN"DL22"3;
"VSS<168>"
$PN"DL4"3;
"VSS<169>"
$PN"DL18"3;
"VSS<170>"
$PN"DL16"3;
"VSS<171>"
$PN"DK85"3;
"VSS<172>"
$PN"DK83"3;
"VSS<173>"
$PN"DK77"3;
"VSS<174>"
$PN"DK75"3;
"VSS<175>"
$PN"DK73"3;
"VSS<176>"
$PN"DK41"3;
"VSS<177>"
$PN"DK39"3;
"VSS<178>"
$PN"DK35"3;
"VSS<179>"
$PN"DK29"3;
"VSS<180>"
$PN"DK23"3;
"VSS<181>"
$PN"DK7"3;
"VSS<182>"
$PN"DJ84"3;
"VSS<183>"
$PN"DJ82"3;
"VSS<184>"
$PN"DJ78"3;
"VSS<185>"
$PN"DJ74"3;
"VSS<186>"
$PN"DJ68"3;
"VSS<187>"
$PN"DJ42"3;
"VSS<188>"
$PN"DJ38"3;
"VSS<189>"
$PN"DJ22"3;
"VSS<190>"
$PN"H47"3;
"VSS<191>"
$PN"DJ10"3;
"VSS<192>"
$PN"DJ2"3;
"VSS<193>"
$PN"DH83"3;
"VSS<194>"
$PN"DH81"3;
"VSS<195>"
$PN"DH79"3;
"VSS<196>"
$PN"DH73"3;
"VSS<197>"
$PN"DH71"3;
"VSS<198>"
$PN"DH67"3;
"VSS<199>"
$PN"DH41"3;
"VSS<200>"
$PN"DH37"3;
"VSS<201>"
$PN"DH35"3;
"VSS<202>"
$PN"DH33"3;
"VSS<203>"
$PN"DH31"3;
"VSS<204>"
$PN"DH29"3;
"VSS<205>"
$PN"DH27"3;
"VSS<206>"
$PN"DH25"3;
"VSS<207>"
$PN"DH23"3;
"VSS<208>"
$PN"DH15"3;
"VSS<209>"
$PN"DH13"3;
"VSS<210>"
$PN"DG82"3;
"VSS<211>"
$PN"DG80"3;
"VSS<212>"
$PN"DG78"3;
"VSS<213>"
$PN"DG76"3;
"VSS<214>"
$PN"DG68"6;
"VSS<215>"
$PN"DG66"6;
"VSS<216>"
$PN"DG24"6;
"VSS<217>"
$PN"DG16"6;
"VSS<218>"
$PN"DG14"6;
"VSS<219>"
$PN"H49"6;
"VSS<220>"
$PN"DG2"6;
"VSS<221>"
$PN"DF85"6;
"VSS<222>"
$PN"DF83"6;
"VSS<223>"
$PN"DF79"6;
"VSS<224>"
$PN"DF73"6;
"VSS<225>"
$PN"DF69"6;
"VSS<226>"
$PN"DF65"6;
"VSS<227>"
$PN"DF41"6;
"VSS<228>"
$PN"DF39"6;
"VSS<229>"
$PN"DF37"6;
"VSS<230>"
$PN"DF35"6;
"VSS<231>"
$PN"DF29"6;
"VSS<232>"
$PN"DF19"6;
"VSS<233>"
$PN"H51"6;
"VSS<234>"
$PN"DF7"6;
"VSS<235>"
$PN"DF5"6;
"VSS<236>"
$PN"DE78"6;
"VSS<237>"
$PN"DE72"6;
"VSS<238>"
$PN"DE70"6;
"VSS<239>"
$PN"DE64"6;
"VSS<240>"
$PN"DE36"6;
"VSS<241>"
$PN"DE34"6;
"VSS<242>"
$PN"DE30"6;
"VSS<243>"
$PN"DE28"6;
"VSS<244>"
$PN"DE24"6;
"VSS<245>"
$PN"DE20"6;
"VSS<246>"
$PN"DE18"6;
"VSS<247>"
$PN"DE8"6;
"VSS<248>"
$PN"DE6"6;
"VSS<249>"
$PN"DD83"6;
"VSS<250>"
$PN"DD81"6;
"VSS<251>"
$PN"DD75"6;
"VSS<252>"
$PN"DD73"6;
"VSS<253>"
$PN"DD71"6;
"VSS<254>"
$PN"DD37"6;
"VSS<255>"
$PN"DD33"6;
"VSS<256>"
$PN"DD31"6;
"VSS<257>"
$PN"DD27"6;
"VSS<258>"
$PN"DD23"6;
"VSS<259>"
$PN"DD11"6;
"VSS<260>"
$PN"DC86"6;
"VSS<261>"
$PN"DC84"6;
"VSS<262>"
$PN"DC78"6;
"VSS<263>"
$PN"DC70"6;
"VSS<264>"
$PN"DC68"6;
"VSS<265>"
$PN"DC66"6;
"VSS<266>"
$PN"DC64"6;
"VSS<267>"
$PN"DC42"6;
"VSS<268>"
$PN"DC38"6;
"VSS<269>"
$PN"DC32"6;
"VSS<270>"
$PN"DC26"6;
"VSS<271>"
$PN"DC24"6;
"VSS<272>"
$PN"DC14"6;
"VSS<273>"
$PN"DB85"6;
"VSS<274>"
$PN"DB83"6;
"VSS<275>"
$PN"DB77"6;
"VSS<276>"
$PN"DB73"6;
"VSS<277>"
$PN"DB49"6;
"VSS<278>"
$PN"DB47"6;
"VSS<279>"
$PN"DB41"6;
"VSS<280>"
$PN"DB39"6;
"VSS<281>"
$PN"DB25"6;
"VSS<282>"
$PN"DB23"6;
"VSS<283>"
$PN"DB17"6;
"VSS<284>"
$PN"DB13"6;
"VSS<285>"
$PN"DB3"6;
"VSS<286>"
$PN"DA80"6;
"VSS<287>"
$PN"DA78"6;
"VSS<288>"
$PN"DA76"6;
"VSS<289>"
$PN"DA74"6;
"VSS<290>"
$PN"DA70"6;
"VSS<291>"
$PN"DA64"6;
"VSS<292>"
$PN"DA50"6;
"VSS<293>"
$PN"DA48"6;
%"SKX_EXT_B"
"30","(-175,2650)","0","chpset_lib","I286";
;
CDS_SEC"30"
LOCATION"U5D1"
PART_NUMBER"TBD"
MATERIAL"IC"
PACK_TYPE"BGA1"
CDS_LIB"chpset_lib"
SEC_TYPE"BGA1"
SEC"30"
CDS_LOCATION"U5D1"
ROOM"CPU0";
"VSS<0>"
$PN"EF79"8;
"VSS<1>"
$PN"EF75"8;
"VSS<2>"
$PN"EF71"8;
"VSS<3>"
$PN"EE78"8;
"VSS<4>"
$PN"EE76"8;
"VSS<5>"
$PN"EE70"8;
"VSS<6>"
$PN"EE36"8;
"VSS<7>"
$PN"EE34"8;
"VSS<8>"
$PN"EE30"8;
"VSS<9>"
$PN"EE28"8;
"VSS<10>"
$PN"EE24"8;
"VSS<11>"
$PN"ED77"8;
"VSS<12>"
$PN"ED35"8;
"VSS<13>"
$PN"ED29"8;
"VSS<14>"
$PN"ED23"8;
"VSS<15>"
$PN"ED15"8;
"VSS<16>"
$PN"ED11"8;
"VSS<17>"
$PN"EC76"8;
"VSS<18>"
$PN"EC74"8;
"VSS<19>"
$PN"EC72"8;
"VSS<20>"
$PN"EC70"8;
"VSS<21>"
$PN"EC10"8;
"VSS<22>"
$PN"EB69"8;
"VSS<23>"
$PN"EB65"8;
"VSS<24>"
$PN"EB41"8;
"VSS<25>"
$PN"EB39"8;
"VSS<26>"
$PN"EB37"8;
"VSS<27>"
$PN"EB35"8;
"VSS<28>"
$PN"EB33"8;
"VSS<29>"
$PN"EB31"8;
"VSS<30>"
$PN"EB29"8;
"VSS<31>"
$PN"EB27"8;
"VSS<32>"
$PN"EB25"8;
"VSS<33>"
$PN"EB23"8;
"VSS<34>"
$PN"BR18"8;
"VSS<35>"
$PN"EB13"8;
"VSS<36>"
$PN"EA82"8;
"VSS<37>"
$PN"EA80"8;
"VSS<38>"
$PN"EA78"8;
"VSS<39>"
$PN"EA76"8;
"VSS<40>"
$PN"EA70"8;
"VSS<41>"
$PN"EA64"8;
"VSS<42>"
$PN"EA42"8;
"VSS<43>"
$PN"EA22"8;
"VSS<44>"
$PN"EA20"8;
"VSS<45>"
$PN"EA16"8;
"VSS<46>"
$PN"J16"8;
"VSS<47>"
$PN"EA6"8;
"VSS<48>"
$PN"DY75"8;
"VSS<49>"
$PN"DY71"8;
"VSS<50>"
$PN"DY41"8;
"VSS<51>"
$PN"DY35"8;
"VSS<52>"
$PN"DY29"8;
"VSS<53>"
$PN"DY23"8;
"VSS<54>"
$PN"DY19"7;
"VSS<55>"
$PN"DY5"7;
"VSS<56>"
$PN"DW84"7;
"VSS<57>"
$PN"DW82"7;
"VSS<58>"
$PN"DW8"7;
"VSS<59>"
$PN"DW76"7;
"VSS<60>"
$PN"DW74"7;
"VSS<61>"
$PN"DW72"7;
"VSS<62>"
$PN"DW70"7;
"VSS<63>"
$PN"DW68"7;
"VSS<64>"
$PN"DW66"7;
"VSS<65>"
$PN"DW64"7;
"VSS<66>"
$PN"DW40"7;
"VSS<67>"
$PN"DW36"7;
"VSS<68>"
$PN"DW34"7;
"VSS<69>"
$PN"DW30"7;
"VSS<70>"
$PN"DW28"7;
"VSS<71>"
$PN"DW24"7;
"VSS<72>"
$PN"DW20"7;
"VSS<73>"
$PN"DW12"7;
"VSS<74>"
$PN"DV81"7;
"VSS<75>"
$PN"DV77"7;
"VSS<76>"
$PN"DV73"7;
"VSS<77>"
$PN"DV39"7;
"VSS<78>"
$PN"DV37"7;
"VSS<79>"
$PN"DV33"7;
"VSS<80>"
$PN"DV31"7;
"VSS<81>"
$PN"DV27"7;
"VSS<82>"
$PN"DV25"7;
"VSS<83>"
$PN"DV21"7;
"VSS<84>"
$PN"DU84"7;
"VSS<85>"
$PN"DU82"7;
"VSS<86>"
$PN"DU80"7;
"VSS<87>"
$PN"DU78"7;
"VSS<88>"
$PN"DU72"7;
"VSS<89>"
$PN"DU70"7;
"VSS<90>"
$PN"DU38"7;
"VSS<91>"
$PN"DU32"7;
"VSS<92>"
$PN"DU26"7;
"VSS<93>"
$PN"DU22"7;
"VSS<94>"
$PN"CN14"7;
"VSS<95>"
$PN"DU14"7;
"VSS<96>"
$PN"DU10"7;
"VSS<97>"
$PN"DT85"7;
"VSS<98>"
$PN"DT83"7;
"VSS<99>"
$PN"DT79"7;
"VSS<100>"
$PN"DT69"7;
"VSS<101>"
$PN"DT65"7;
"VSS<102>"
$PN"DH21"7;
"VSS<103>"
$PN"DT17"7;
"VSS<104>"
$PN"DT3"7;
"VSS<105>"
$PN"DR78"7;
"VSS<106>"
$PN"DR76"7;
"VSS<107>"
$PN"DR74"7;
"VSS<108>"
$PN"DR72"7;
"VSS<109>"
$PN"DR70"7;
"VSS<110>"
$PN"DR68"7;
"VSS<111>"
$PN"DR66"7;
"VSS<112>"
$PN"DR42"7;
"VSS<113>"
$PN"DR40"7;
"VSS<114>"
$PN"DR38"7;
"VSS<115>"
$PN"DR36"7;
"VSS<116>"
$PN"DR34"7;
"VSS<117>"
$PN"DR32"7;
"VSS<118>"
$PN"DR30"7;
"VSS<119>"
$PN"DR28"7;
"VSS<120>"
$PN"DR26"7;
"VSS<121>"
$PN"DR24"7;
"VSS<122>"
$PN"DR22"7;
"VSS<123>"
$PN"DR20"7;
"VSS<124>"
$PN"CL22"7;
"VSS<125>"
$PN"CA20"7;
"VSS<126>"
$PN"DR6"7;
"VSS<127>"
$PN"BR26"7;
"VSS<128>"
$PN"DP83"7;
"VSS<129>"
$PN"DP81"7;
"VSS<130>"
$PN"DP71"7;
"VSS<131>"
$PN"DP69"7;
"VSS<132>"
$PN"DP67"7;
"VSS<133>"
$PN"DN78"7;
END.
